(kicad_pcb
	(version 20260206)
	(generator "pcbnew")
	(generator_version "10.0")
	(general
		(thickness 1.6)
		(legacy_teardrops no)
	)
	(paper "A4")
	(title_block
		(title "Bryce Canyon_R.DPB_16317-1_OCP.brd")
		(comment 1 "Bryce Canyon / footprints 1824-1830 of 2099")
	)
	(layers
		(0 "F.Cu" signal "TOP")
		(4 "In1.Cu" signal "L2GND")
		(6 "In2.Cu" signal "L3")
		(8 "In3.Cu" signal "L4VCC")
		(10 "In4.Cu" signal "L5VCC")
		(12 "In5.Cu" signal "L6")
		(14 "In6.Cu" signal "L7GND")
		(2 "B.Cu" signal "BOTTOM")
		(9 "F.Adhes" user "F.Adhesive")
		(11 "B.Adhes" user "B.Adhesive")
		(13 "F.Paste" user "Package Geometry/Pastemask Top")
		(15 "B.Paste" user "Package Geometry/Pastemask Bottom")
		(5 "F.SilkS" user "Ref Des/Silkscreen Top")
		(7 "B.SilkS" user "Ref Des/Silkscreen Bottom")
		(1 "F.Mask" user "Board Geometry/Soldermask Top")
		(3 "B.Mask" user "Board Geometry/Soldermask Bottom")
		(17 "Dwgs.User" user "User.Drawings")
		(19 "Cmts.User" user "User.Comments")
		(21 "Eco1.User" user "User.Eco1")
		(23 "Eco2.User" user "User.Eco2")
		(25 "Edge.Cuts" user "Board Geometry/Outline")
		(27 "Margin" user)
		(31 "F.CrtYd" user "Package Geometry/Place Bound Top")
		(29 "B.CrtYd" user "Package Geometry/Place Bound Bottom")
		(35 "F.Fab" user "Ref Des/Assembly Top")
		(33 "B.Fab" user "Ref Des/Assembly Bottom")
	)
	(footprint ""
		(layer "F.Cu")
		(at 259.700522 -362.305346 90)
		(property "Reference" "R1030"
			(at 0 0 90)
			(layer "F.SilkS")
			(hide yes)
			(effects
				(font
					(size 1.27 1.27)
				)
			)
		)
		(property "Value" "0R2J-2-GP"
			(at 0.064008 -3.993896 90)
			(unlocked yes)
			(layer "F.Fab")
			(hide yes)
			(effects
				(font
					(size 1.016 1.016)
					(thickness 0.1524)
				)
			)
		)
		(property "Device Type" "R402H16"
			(at 0.064008 -5.517896 90)
			(unlocked yes)
			(layer "F.Fab")
			(hide yes)
			(effects
				(font
					(size 1.016 1.016)
					(thickness 0.1524)
				)
			)
		)
		(duplicate_pad_numbers_are_jumpers no)
		(fp_line
			(start 0.508 -0.9398)
			(end -0.508 -0.9398)
			(stroke
				(width 0.1524)
				(type default)
			)
			(layer "F.SilkS")
		)
		(fp_line
			(start -0.508 -0.9398)
			(end -0.508 0.9398)
			(stroke
				(width 0.1524)
				(type default)
			)
			(layer "F.SilkS")
		)
		(fp_rect
			(start -0.508 0.9398)
			(end 0.508 -0.9398)
			(stroke
				(width 0)
				(type default)
			)
			(fill no)
			(layer "F.CrtYd")
		)
		(fp_rect
			(start -0.508 0.9398)
			(end 0.508 -0.9398)
			(stroke
				(width 0)
				(type default)
			)
			(fill no)
			(layer "F.Fab")
		)
		(pad "1" smd custom
			(at 0 -0.4445 90)
			(size 0.1397 0.1397)
			(layers "F.Cu" "F.Mask" "F.Paste")
			(net "MB3_CM_ADR2_R")
			(options
				(clearance outline)
				(anchor circle)
			)
			(primitives
				(gr_poly
					(pts
						(arc
							(start -0.1778 -0.2794)
							(mid -0.249642 -0.249642)
							(end -0.2794 -0.1778)
						)
						(arc
							(start -0.2794 0.1778)
							(mid -0.249642 0.249642)
							(end -0.1778 0.2794)
						)
						(arc
							(start 0.1778 0.2794)
							(mid 0.249642 0.249642)
							(end 0.2794 0.1778)
						)
						(arc
							(start 0.2794 -0.1778)
							(mid 0.249642 -0.249642)
							(end 0.1778 -0.2794)
						)
					)
					(width 0)
					(fill yes)
				)
			)
		)
		(pad "2" smd custom
			(at 0 0.4445 90)
			(size 0.1397 0.1397)
			(layers "F.Cu" "F.Mask" "F.Paste")
			(net "AGND_CURRENT_DPB")
			(options
				(clearance outline)
				(anchor circle)
			)
			(primitives
				(gr_poly
					(pts
						(arc
							(start -0.1778 -0.2794)
							(mid -0.249642 -0.249642)
							(end -0.2794 -0.1778)
						)
						(arc
							(start -0.2794 0.1778)
							(mid -0.249642 0.249642)
							(end -0.1778 0.2794)
						)
						(arc
							(start 0.1778 0.2794)
							(mid 0.249642 0.249642)
							(end 0.2794 0.1778)
						)
						(arc
							(start 0.2794 -0.1778)
							(mid 0.249642 -0.249642)
							(end 0.1778 -0.2794)
						)
					)
					(width 0)
					(fill yes)
				)
			)
		)
	)
	(footprint ""
		(layer "F.Cu")
		(at 347.345 -99.187)
		(property "Reference" "R435"
			(at 0 0 0)
			(layer "F.SilkS")
			(hide yes)
			(effects
				(font
					(size 1.27 1.27)
				)
			)
		)
		(property "Value" "91R3F-1-GP"
			(at -0.0254 -2.5146 0)
			(unlocked yes)
			(layer "F.Fab")
			(hide yes)
			(effects
				(font
					(size 1.016 1.016)
					(thickness 0.1524)
				)
			)
		)
		(property "Device Type" "R603H22"
			(at -0.0254 -4.0386 0)
			(unlocked yes)
			(layer "F.Fab")
			(hide yes)
			(effects
				(font
					(size 1.016 1.016)
					(thickness 0.1524)
				)
			)
		)
		(duplicate_pad_numbers_are_jumpers no)
		(fp_line
			(start -0.4826 0)
			(end -0.2032 0)
			(stroke
				(width 0.2032)
				(type default)
			)
			(layer "F.SilkS")
		)
		(fp_line
			(start 0.2032 0)
			(end 0.4826 0)
			(stroke
				(width 0.2032)
				(type default)
			)
			(layer "F.SilkS")
		)
		(fp_rect
			(start -0.5842 1.3335)
			(end 0.5842 -1.3335)
			(stroke
				(width 0)
				(type default)
			)
			(fill no)
			(layer "F.CrtYd")
		)
		(fp_rect
			(start -0.5842 1.3335)
			(end 0.5842 -1.3335)
			(stroke
				(width 0)
				(type default)
			)
			(fill no)
			(layer "F.Fab")
		)
		(pad "1" smd custom
			(at 0 -0.762)
			(size 0.2159 0.2159)
			(layers "F.Cu" "F.Mask" "F.Paste")
			(net "P5V_B_3")
			(options
				(clearance outline)
				(anchor circle)
			)
			(primitives
				(gr_poly
					(pts
						(arc
							(start -0.3302 -0.4318)
							(mid -0.402042 -0.402042)
							(end -0.4318 -0.3302)
						)
						(arc
							(start -0.4318 0.3302)
							(mid -0.402042 0.402042)
							(end -0.3302 0.4318)
						)
						(arc
							(start 0.3302 0.4318)
							(mid 0.402042 0.402042)
							(end 0.4318 0.3302)
						)
						(arc
							(start 0.4318 -0.3302)
							(mid 0.402042 -0.402042)
							(end 0.3302 -0.4318)
						)
					)
					(width 0)
					(fill yes)
				)
			)
		)
		(pad "2" smd custom
			(at 0 0.762)
			(size 0.2159 0.2159)
			(layers "F.Cu" "F.Mask" "F.Paste")
			(net "DRV_ACT_19")
			(options
				(clearance outline)
				(anchor circle)
			)
			(primitives
				(gr_poly
					(pts
						(arc
							(start -0.3302 -0.4318)
							(mid -0.402042 -0.402042)
							(end -0.4318 -0.3302)
						)
						(arc
							(start -0.4318 0.3302)
							(mid -0.402042 0.402042)
							(end -0.3302 0.4318)
						)
						(arc
							(start 0.3302 0.4318)
							(mid 0.402042 0.402042)
							(end 0.4318 0.3302)
						)
						(arc
							(start 0.4318 -0.3302)
							(mid 0.402042 -0.402042)
							(end 0.3302 -0.4318)
						)
					)
					(width 0)
					(fill yes)
				)
			)
		)
	)
	(footprint ""
		(layer "F.Cu")
		(at 458.47 -36.83 180)
		(property "Reference" "C473"
			(at 0 0 180)
			(layer "F.SilkS")
			(hide yes)
			(effects
				(font
					(size 1.27 1.27)
				)
			)
		)
		(property "Value" "SC10U16V6KX-2GP"
			(at -0.0762 -5.1308 180)
			(unlocked yes)
			(layer "F.Fab")
			(hide yes)
			(effects
				(font
					(size 1.016 1.016)
					(thickness 0.1524)
				)
			)
		)
		(property "Device Type" "C1206H71"
			(at -0.127 -6.6548 180)
			(unlocked yes)
			(layer "F.Fab")
			(hide yes)
			(effects
				(font
					(size 1.016 1.016)
					(thickness 0.1524)
				)
			)
		)
		(duplicate_pad_numbers_are_jumpers no)
		(fp_line
			(start 1.016 2.2352)
			(end -1.016 2.2352)
			(stroke
				(width 0.1524)
				(type default)
			)
			(layer "F.SilkS")
		)
		(fp_line
			(start 1.016 0.8382)
			(end 1.016 2.2352)
			(stroke
				(width 0.1524)
				(type default)
			)
			(layer "F.SilkS")
		)
		(fp_line
			(start 1.016 -2.2352)
			(end 1.016 -0.8382)
			(stroke
				(width 0.1524)
				(type default)
			)
			(layer "F.SilkS")
		)
		(fp_line
			(start -1.016 2.2352)
			(end -1.016 0.8382)
			(stroke
				(width 0.1524)
				(type default)
			)
			(layer "F.SilkS")
		)
		(fp_line
			(start -1.016 -0.8382)
			(end -1.016 -2.2352)
			(stroke
				(width 0.1524)
				(type default)
			)
			(layer "F.SilkS")
		)
		(fp_line
			(start -1.016 -2.2352)
			(end 1.016 -2.2352)
			(stroke
				(width 0.1524)
				(type default)
			)
			(layer "F.SilkS")
		)
		(fp_rect
			(start -1.0922 2.3114)
			(end 1.0922 -2.3114)
			(stroke
				(width 0)
				(type default)
			)
			(fill no)
			(layer "F.CrtYd")
		)
		(fp_poly
			(pts
				(xy 1.0922 -2.3114) (xy 1.0922 2.3114) (xy -1.0922 2.3114) (xy -1.0922 -2.3114)
			)
			(stroke
				(width 0)
				(type default)
			)
			(fill no)
			(layer "F.Fab")
		)
		(pad "1" smd rect
			(at 0 -1.397 180)
			(size 1.651 1.27)
			(layers "F.Cu" "F.Mask" "F.Paste")
			(net "P5V_HDD34")
		)
		(pad "2" smd rect
			(at 0 1.397 180)
			(size 1.651 1.27)
			(layers "F.Cu" "F.Mask" "F.Paste")
			(net "GND")
		)
	)
	(footprint ""
		(layer "F.Cu")
		(at 426.72 -246.253 -90)
		(property "Reference" "Q35"
			(at 0 0 270)
			(layer "F.SilkS")
			(hide yes)
			(effects
				(font
					(size 1.27 1.27)
				)
			)
		)
		(property "Value" "2N7002KDW-GP"
			(at -2.3622 -8.2042 270)
			(unlocked yes)
			(layer "F.Fab")
			(hide yes)
			(effects
				(font
					(size 1.016 1.016)
					(thickness 0.1524)
				)
			)
		)
		(property "Device Type" "SOT-363H44"
			(at -2.3622 -10.1092 270)
			(unlocked yes)
			(layer "F.Fab")
			(hide yes)
			(effects
				(font
					(size 1.016 1.016)
					(thickness 0.1524)
				)
			)
		)
		(duplicate_pad_numbers_are_jumpers no)
		(fp_line
			(start -1.4478 1.7018)
			(end 1.4478 1.7018)
			(stroke
				(width 0.1524)
				(type default)
			)
			(layer "F.SilkS")
		)
		(fp_line
			(start 1.4478 1.7018)
			(end 1.4478 -1.7018)
			(stroke
				(width 0.1524)
				(type default)
			)
			(layer "F.SilkS")
		)
		(fp_line
			(start -1.27 1.524)
			(end -1.27 0.6604)
			(stroke
				(width 0.4826)
				(type default)
			)
			(layer "F.SilkS")
		)
		(fp_line
			(start -1.4478 -1.7018)
			(end -1.4478 1.7018)
			(stroke
				(width 0.1524)
				(type default)
			)
			(layer "F.SilkS")
		)
		(fp_line
			(start 1.4478 -1.7018)
			(end -1.4478 -1.7018)
			(stroke
				(width 0.1524)
				(type default)
			)
			(layer "F.SilkS")
		)
		(fp_poly
			(pts
				(xy -1.524 -1.778) (xy 1.524 -1.778) (xy 1.524 1.778) (xy -1.524 1.778)
			)
			(stroke
				(width 0)
				(type default)
			)
			(fill no)
			(layer "F.CrtYd")
		)
		(fp_poly
			(pts
				(xy -1.524 -1.778) (xy 1.524 -1.778) (xy 1.524 1.778) (xy -1.524 1.778)
			)
			(stroke
				(width 0)
				(type default)
			)
			(fill no)
			(layer "F.Fab")
		)
		(pad "1" smd rect
			(at -0.65024 0.9398 270)
			(size 0.4064 1.016)
			(layers "F.Cu" "F.Mask" "F.Paste")
			(net "GND")
		)
		(pad "2" smd rect
			(at 0 0.9398 270)
			(size 0.4064 1.016)
			(layers "F.Cu" "F.Mask" "F.Paste")
			(net "SW_PWR_R_HDD9")
		)
		(pad "3" smd rect
			(at 0.65024 0.9398 270)
			(size 0.4064 1.016)
			(layers "F.Cu" "F.Mask" "F.Paste")
			(net "SW_HDD_P9")
		)
		(pad "4" smd rect
			(at 0.65024 -0.9398 270)
			(size 0.4064 1.016)
			(layers "F.Cu" "F.Mask" "F.Paste")
			(net "GND")
		)
		(pad "5" smd rect
			(at 0 -0.9398 270)
			(size 0.4064 1.016)
			(layers "F.Cu" "F.Mask" "F.Paste")
			(net "SW_HDD_G9")
		)
		(pad "6" smd rect
			(at -0.65024 -0.9398 270)
			(size 0.4064 1.016)
			(layers "F.Cu" "F.Mask" "F.Paste")
			(net "SW_HDD_R9")
		)
	)
	(footprint ""
		(layer "F.Cu")
		(at 35.654996 -368.935 -90)
		(property "Reference" "R926"
			(at 0 0 270)
			(layer "F.SilkS")
			(hide yes)
			(effects
				(font
					(size 1.27 1.27)
				)
			)
		)
		(property "Value" "10KR2F-2-GP"
			(at 0.064008 -3.993896 270)
			(unlocked yes)
			(layer "F.Fab")
			(hide yes)
			(effects
				(font
					(size 1.016 1.016)
					(thickness 0.1524)
				)
			)
		)
		(property "Device Type" "R402H16"
			(at 0.064008 -5.517896 270)
			(unlocked yes)
			(layer "F.Fab")
			(hide yes)
			(effects
				(font
					(size 1.016 1.016)
					(thickness 0.1524)
				)
			)
		)
		(duplicate_pad_numbers_are_jumpers no)
		(fp_line
			(start -0.508 -0.9398)
			(end -0.508 0.9398)
			(stroke
				(width 0.1524)
				(type default)
			)
			(layer "F.SilkS")
		)
		(fp_line
			(start 0.508 -0.9398)
			(end -0.508 -0.9398)
			(stroke
				(width 0.1524)
				(type default)
			)
			(layer "F.SilkS")
		)
		(fp_rect
			(start -0.508 0.9398)
			(end 0.508 -0.9398)
			(stroke
				(width 0)
				(type default)
			)
			(fill no)
			(layer "F.CrtYd")
		)
		(fp_rect
			(start -0.508 0.9398)
			(end 0.508 -0.9398)
			(stroke
				(width 0)
				(type default)
			)
			(fill no)
			(layer "F.Fab")
		)
		(pad "1" smd custom
			(at 0 -0.4445 270)
			(size 0.1397 0.1397)
			(layers "F.Cu" "F.Mask" "F.Paste")
			(net "GND")
			(options
				(clearance outline)
				(anchor circle)
			)
			(primitives
				(gr_poly
					(pts
						(arc
							(start -0.1778 -0.2794)
							(mid -0.249642 -0.249642)
							(end -0.2794 -0.1778)
						)
						(arc
							(start -0.2794 0.1778)
							(mid -0.249642 0.249642)
							(end -0.1778 0.2794)
						)
						(arc
							(start 0.1778 0.2794)
							(mid 0.249642 0.249642)
							(end 0.2794 0.1778)
						)
						(arc
							(start 0.2794 -0.1778)
							(mid 0.249642 -0.249642)
							(end 0.1778 -0.2794)
						)
					)
					(width 0)
					(fill yes)
				)
			)
		)
		(pad "2" smd custom
			(at 0 0.4445 270)
			(size 0.1397 0.1397)
			(layers "F.Cu" "F.Mask" "F.Paste")
			(net "FANTACH_R0")
			(options
				(clearance outline)
				(anchor circle)
			)
			(primitives
				(gr_poly
					(pts
						(arc
							(start -0.1778 -0.2794)
							(mid -0.249642 -0.249642)
							(end -0.2794 -0.1778)
						)
						(arc
							(start -0.2794 0.1778)
							(mid -0.249642 0.249642)
							(end -0.1778 0.2794)
						)
						(arc
							(start 0.1778 0.2794)
							(mid 0.249642 0.249642)
							(end 0.2794 0.1778)
						)
						(arc
							(start 0.2794 -0.1778)
							(mid 0.249642 -0.249642)
							(end 0.1778 -0.2794)
						)
					)
					(width 0)
					(fill yes)
				)
			)
		)
	)
	(footprint ""
		(layer "F.Cu")
		(at 37.5158 -7.4422 90)
		(property "Reference" "C29"
			(at 0 0 90)
			(layer "F.SilkS")
			(hide yes)
			(effects
				(font
					(size 1.27 1.27)
				)
			)
		)
		(property "Value" "SC1U16V3KX-5GP"
			(at 0 -2.8194 90)
			(unlocked yes)
			(layer "F.Fab")
			(hide yes)
			(effects
				(font
					(size 1.016 1.016)
					(thickness 0.1524)
				)
			)
		)
		(property "Device Type" "C603H36"
			(at 0 -4.3434 90)
			(unlocked yes)
			(layer "F.Fab")
			(hide yes)
			(effects
				(font
					(size 1.016 1.016)
					(thickness 0.1524)
				)
			)
		)
		(duplicate_pad_numbers_are_jumpers no)
		(fp_line
			(start 0.508 0)
			(end -0.508 0)
			(stroke
				(width 0.2032)
				(type default)
			)
			(layer "F.SilkS")
		)
		(fp_rect
			(start -0.5842 1.3335)
			(end 0.5842 -1.3335)
			(stroke
				(width 0)
				(type default)
			)
			(fill no)
			(layer "F.CrtYd")
		)
		(fp_rect
			(start -0.5842 1.3335)
			(end 0.5842 -1.3335)
			(stroke
				(width 0)
				(type default)
			)
			(fill no)
			(layer "F.Fab")
		)
		(pad "1" smd custom
			(at 0 -0.762 90)
			(size 0.2159 0.2159)
			(layers "F.Cu" "F.Mask" "F.Paste")
			(net "P3V3_STBY_A")
			(options
				(clearance outline)
				(anchor circle)
			)
			(primitives
				(gr_poly
					(pts
						(arc
							(start -0.3302 -0.4318)
							(mid -0.402042 -0.402042)
							(end -0.4318 -0.3302)
						)
						(arc
							(start -0.4318 0.3302)
							(mid -0.402042 0.402042)
							(end -0.3302 0.4318)
						)
						(arc
							(start 0.3302 0.4318)
							(mid 0.402042 0.402042)
							(end 0.4318 0.3302)
						)
						(arc
							(start 0.4318 -0.3302)
							(mid 0.402042 -0.402042)
							(end 0.3302 -0.4318)
						)
					)
					(width 0)
					(fill yes)
				)
			)
		)
		(pad "2" smd custom
			(at 0 0.762 90)
			(size 0.2159 0.2159)
			(layers "F.Cu" "F.Mask" "F.Paste")
			(net "GND")
			(options
				(clearance outline)
				(anchor circle)
			)
			(primitives
				(gr_poly
					(pts
						(arc
							(start -0.3302 -0.4318)
							(mid -0.402042 -0.402042)
							(end -0.4318 -0.3302)
						)
						(arc
							(start -0.4318 0.3302)
							(mid -0.402042 0.402042)
							(end -0.3302 0.4318)
						)
						(arc
							(start 0.3302 0.4318)
							(mid 0.402042 0.402042)
							(end 0.4318 0.3302)
						)
						(arc
							(start 0.4318 -0.3302)
							(mid 0.402042 -0.402042)
							(end 0.3302 -0.4318)
						)
					)
					(width 0)
					(fill yes)
				)
			)
		)
	)
	(footprint ""
		(layer "F.Cu")
		(at 398.78 -16.383 180)
		(property "Reference" "D32"
			(at 0 0 180)
			(layer "F.SilkS")
			(hide yes)
			(effects
				(font
					(size 1.27 1.27)
				)
			)
		)
		(property "Value" "RB551V30-GP"
			(at 0 -6.7818 180)
			(unlocked yes)
			(layer "F.Fab")
			(hide yes)
			(effects
				(font
					(size 1.016 1.016)
					(thickness 0.1524)
				)
			)
		)
		(property "Device Type" "SOD323AKH38"
			(at 0 -8.6868 180)
			(unlocked yes)
			(layer "F.Fab")
			(hide yes)
			(effects
				(font
					(size 1.016 1.016)
					(thickness 0.1524)
				)
			)
		)
		(duplicate_pad_numbers_are_jumpers no)
		(fp_line
			(start 0.889 2.159)
			(end -0.889 2.159)
			(stroke
				(width 0.1524)
				(type default)
			)
			(layer "F.SilkS")
		)
		(fp_line
			(start 0.889 -1.9304)
			(end 0.889 2.159)
			(stroke
				(width 0.1524)
				(type default)
			)
			(layer "F.SilkS")
		)
		(fp_line
			(start 0.762 2.0574)
			(end -0.762 2.0574)
			(stroke
				(width 0.508)
				(type default)
			)
			(layer "F.SilkS")
		)
		(fp_line
			(start -0.889 2.159)
			(end -0.889 -1.9304)
			(stroke
				(width 0.1524)
				(type default)
			)
			(layer "F.SilkS")
		)
		(fp_line
			(start -0.889 -1.9304)
			(end 0.889 -1.9304)
			(stroke
				(width 0.1524)
				(type default)
			)
			(layer "F.SilkS")
		)
		(fp_rect
			(start -1.016 2.3114)
			(end 1.016 -2.0066)
			(stroke
				(width 0)
				(type default)
			)
			(fill no)
			(layer "F.CrtYd")
		)
		(fp_poly
			(pts
				(xy -1.016 -2.0066) (xy 1.016 -2.0066) (xy 1.016 2.3114) (xy -1.016 2.3114)
			)
			(stroke
				(width 0)
				(type default)
			)
			(fill no)
			(layer "F.Fab")
		)
		(pad "A" smd rect
			(at 0 -1.143 180)
			(size 0.5588 1.016)
			(layers "F.Cu" "F.Mask" "F.Paste")
			(net "SW_HDD_R32")
		)
		(pad "K" smd rect
			(at 0 1.143 180)
			(size 0.5588 1.016)
			(layers "F.Cu" "F.Mask" "F.Paste")
			(net "SW_HDD_N32")
		)
	)
)
